(kicad_pcb
	(version 20260206)
	(generator "pcbnew")
	(generator_version "10.0")
	(general
		(thickness 1.6)
		(legacy_teardrops no)
	)
	(paper "A4")
	(title_block
		(title "Wiwynn_Tioga_Pass_MB.brd")
		(comment 1 "Tioga Pass / footprints 1334-1340 of 4770")
	)
	(layers
		(0 "F.Cu" signal "TOP")
		(4 "In1.Cu" signal "L2GND")
		(6 "In2.Cu" signal "L3")
		(8 "In3.Cu" signal "L4GND")
		(10 "In4.Cu" signal "L5")
		(12 "In5.Cu" signal "L6GND")
		(14 "In6.Cu" signal "L7VCC")
		(16 "In7.Cu" signal "L8VCC")
		(18 "In8.Cu" signal "L9GND")
		(20 "In9.Cu" signal "L10")
		(22 "In10.Cu" signal "L11GND")
		(24 "In11.Cu" signal "L12")
		(26 "In12.Cu" signal "L13GND")
		(2 "B.Cu" signal "BOTTOM")
		(9 "F.Adhes" user "F.Adhesive")
		(11 "B.Adhes" user "B.Adhesive")
		(13 "F.Paste" user "Package Geometry/Pastemask Top")
		(15 "B.Paste" user "Package Geometry/Pastemask Bottom")
		(5 "F.SilkS" user "Ref Des/Silkscreen Top")
		(7 "B.SilkS" user "Ref Des/Silkscreen Bottom")
		(1 "F.Mask" user "Board Geometry/Soldermask Top")
		(3 "B.Mask" user "Board Geometry/Soldermask Bottom")
		(17 "Dwgs.User" user "User.Drawings")
		(19 "Cmts.User" user "User.Comments")
		(21 "Eco1.User" user "User.Eco1")
		(23 "Eco2.User" user "User.Eco2")
		(25 "Edge.Cuts" user "Board Geometry/Outline")
		(27 "Margin" user)
		(31 "F.CrtYd" user "Package Geometry/Place Bound Top")
		(29 "B.CrtYd" user "Package Geometry/Place Bound Bottom")
		(35 "F.Fab" user "Ref Des/Assembly Top")
		(33 "B.Fab" user "Ref Des/Assembly Bottom")
	)
	(footprint ""
		(layer "F.Cu")
		(at 369.333526 -105.198164 90)
		(property "Reference" "R7C2"
			(at 0 0 90)
			(layer "F.SilkS")
			(hide yes)
			(effects
				(font
					(size 1.27 1.27)
				)
			)
		)
		(property "Value" ""
			(at 0 0 90)
			(layer "F.Fab")
			(effects
				(font
					(size 1.27 1.27)
				)
			)
		)
		(duplicate_pad_numbers_are_jumpers no)
		(fp_poly
			(pts
				(xy -0.2794 -0.1016) (xy 0.2794 -0.1016) (xy 0.2794 0.9906) (xy -0.2794 0.9906)
			)
			(stroke
				(width 0)
				(type default)
			)
			(fill no)
			(layer "F.CrtYd")
		)
		(fp_line
			(start 0.2794 -0.1016)
			(end -0.2794 -0.1016)
			(stroke
				(width 0.1)
				(type default)
			)
			(layer "F.Fab")
		)
		(fp_line
			(start -0.2794 -0.1016)
			(end -0.2794 0.9906)
			(stroke
				(width 0.1)
				(type default)
			)
			(layer "F.Fab")
		)
		(fp_line
			(start 0.2794 0.9906)
			(end 0.2794 -0.1016)
			(stroke
				(width 0.1)
				(type default)
			)
			(layer "F.Fab")
		)
		(fp_line
			(start -0.2794 0.9906)
			(end 0.2794 0.9906)
			(stroke
				(width 0.1)
				(type default)
			)
			(layer "F.Fab")
		)
		(pad "1" smd rect
			(at 0 0 90)
			(size 0.508 0.508)
			(layers "F.Cu" "F.Mask" "F.Paste")
			(net "CLK_100M_BMC_PE_R_DN")
		)
		(pad "2" smd rect
			(at 0 0.889 90)
			(size 0.508 0.508)
			(layers "F.Cu" "F.Mask" "F.Paste")
			(net "CLK_100M_BMC_PE_DN")
		)
		(zone
			(layer "F.Cu")
			(hatch none 0.5)
			(connect_pads
				(clearance 0)
			)
			(min_thickness 0.25)
			(keepout
				(tracks allowed)
				(vias not_allowed)
				(pads allowed)
				(copperpour not_allowed)
				(footprints allowed)
			)
			(placement
				(enabled no)
				(sheetname "")
			)
			(fill
				(thermal_gap 0.5)
				(thermal_bridge_width 0.5)
				(island_removal_mode 0)
			)
			(polygon
				(pts
					(xy 369.587526 -104.944164) (xy 369.587526 -105.452164) (xy 369.968526 -105.452164) (xy 369.968526 -104.944164)
				)
			)
		)
		(zone
			(layer "F.Cu")
			(hatch none 0.5)
			(connect_pads
				(clearance 0)
			)
			(min_thickness 0.25)
			(keepout
				(tracks not_allowed)
				(vias allowed)
				(pads allowed)
				(copperpour not_allowed)
				(footprints allowed)
			)
			(placement
				(enabled no)
				(sheetname "")
			)
			(fill
				(thermal_gap 0.5)
				(thermal_bridge_width 0.5)
				(island_removal_mode 0)
			)
			(polygon
				(pts
					(xy 369.968526 -104.944164) (xy 369.968526 -105.452164) (xy 369.587526 -105.452164) (xy 369.587526 -104.944164)
				)
			)
		)
	)
	(footprint ""
		(layer "F.Cu")
		(at 324.5485 -120.396 -90)
		(property "Reference" "C829"
			(at -0.8382 -0.67818 270)
			(unlocked yes)
			(layer "F.SilkS")
			(effects
				(font
					(size 0.4064 0.254)
					(thickness 0.1524)
				)
				(justify left)
			)
		)
		(property "Value" ""
			(at 0 0 270)
			(layer "F.Fab")
			(effects
				(font
					(size 1.27 1.27)
				)
			)
		)
		(duplicate_pad_numbers_are_jumpers no)
		(fp_poly
			(pts
				(xy 0.3048 -0.1016) (xy 0.3048 0.9906) (xy -0.3048 0.9906) (xy -0.3048 -0.1016)
			)
			(stroke
				(width 0)
				(type default)
			)
			(fill no)
			(layer "F.CrtYd")
		)
		(fp_line
			(start -0.3048 0.9906)
			(end 0.3048 0.9906)
			(stroke
				(width 0.1)
				(type default)
			)
			(layer "F.Fab")
		)
		(fp_line
			(start 0.3048 0.9906)
			(end 0.3048 -0.1016)
			(stroke
				(width 0.1)
				(type default)
			)
			(layer "F.Fab")
		)
		(fp_line
			(start -0.3048 -0.1016)
			(end -0.3048 0.9906)
			(stroke
				(width 0.1)
				(type default)
			)
			(layer "F.Fab")
		)
		(fp_line
			(start 0.3048 -0.1016)
			(end -0.3048 -0.1016)
			(stroke
				(width 0.1)
				(type default)
			)
			(layer "F.Fab")
		)
		(pad "1" smd rect
			(at 0 0 270)
			(size 0.508 0.508)
			(layers "F.Cu" "F.Mask" "F.Paste")
			(net "P3E_CPU0_PE1_PCH_TXP<13>")
		)
		(pad "2" smd rect
			(at 0 0.889 270)
			(size 0.508 0.508)
			(layers "F.Cu" "F.Mask" "F.Paste")
			(net "P3E_CPU0_PE1_PCH_CON_TXP<13>")
		)
		(zone
			(layer "F.Cu")
			(hatch none 0.5)
			(connect_pads
				(clearance 0)
			)
			(min_thickness 0.25)
			(keepout
				(tracks allowed)
				(vias not_allowed)
				(pads allowed)
				(copperpour not_allowed)
				(footprints allowed)
			)
			(placement
				(enabled no)
				(sheetname "")
			)
			(fill
				(thermal_gap 0.5)
				(thermal_bridge_width 0.5)
				(island_removal_mode 0)
			)
			(polygon
				(pts
					(xy 324.2945 -120.65) (xy 324.2945 -120.142) (xy 323.9135 -120.142) (xy 323.9135 -120.65)
				)
			)
		)
	)
	(footprint ""
		(layer "F.Cu")
		(at 49.4284 -70.993)
		(property "Reference" "C1D24"
			(at 0 0 0)
			(layer "F.SilkS")
			(hide yes)
			(effects
				(font
					(size 1.27 1.27)
				)
			)
		)
		(property "Value" ""
			(at 0 0 0)
			(layer "F.Fab")
			(effects
				(font
					(size 1.27 1.27)
				)
			)
		)
		(duplicate_pad_numbers_are_jumpers no)
		(fp_poly
			(pts
				(xy -0.4953 -0.2032) (xy 0.4953 -0.2032) (xy 0.4953 1.6002) (xy -0.4953 1.6002)
			)
			(stroke
				(width 0)
				(type default)
			)
			(fill no)
			(layer "F.CrtYd")
		)
		(fp_line
			(start -0.4953 -0.2032)
			(end 0.4953 -0.2032)
			(stroke
				(width 0.1)
				(type default)
			)
			(layer "F.Fab")
		)
		(fp_line
			(start -0.4953 1.6002)
			(end -0.4953 -0.2032)
			(stroke
				(width 0.1)
				(type default)
			)
			(layer "F.Fab")
		)
		(fp_line
			(start 0.4953 -0.2032)
			(end 0.4953 1.6002)
			(stroke
				(width 0.1)
				(type default)
			)
			(layer "F.Fab")
		)
		(fp_line
			(start 0.4953 1.6002)
			(end -0.4953 1.6002)
			(stroke
				(width 0.1)
				(type default)
			)
			(layer "F.Fab")
		)
		(pad "1" smd rect
			(at 0 0)
			(size 0.762 0.889)
			(layers "F.Cu" "F.Mask" "F.Paste")
			(net "PVCCIN_CPU1")
		)
		(pad "2" smd rect
			(at 0 1.397)
			(size 0.762 0.889)
			(layers "F.Cu" "F.Mask" "F.Paste")
			(net "GND")
		)
		(zone
			(layer "F.Cu")
			(hatch none 0.5)
			(connect_pads
				(clearance 0)
			)
			(min_thickness 0.25)
			(keepout
				(tracks not_allowed)
				(vias allowed)
				(pads allowed)
				(copperpour not_allowed)
				(footprints allowed)
			)
			(placement
				(enabled no)
				(sheetname "")
			)
			(fill
				(thermal_gap 0.5)
				(thermal_bridge_width 0.5)
				(island_removal_mode 0)
			)
			(polygon
				(pts
					(xy 49.0474 -70.5485) (xy 49.8094 -70.5485) (xy 49.8094 -70.0405) (xy 49.0474 -70.0405)
				)
			)
		)
	)
	(footprint ""
		(layer "F.Cu")
		(at 488.3912 -22.1996 180)
		(property "Reference" "R25W156"
			(at -0.8382 -0.67818 180)
			(unlocked yes)
			(layer "F.SilkS")
			(effects
				(font
					(size 0.4064 0.254)
					(thickness 0.1524)
				)
				(justify left)
			)
		)
		(property "Value" ""
			(at 0 0 180)
			(layer "F.Fab")
			(effects
				(font
					(size 1.27 1.27)
				)
			)
		)
		(duplicate_pad_numbers_are_jumpers no)
		(fp_poly
			(pts
				(xy -0.2794 -0.1016) (xy 0.2794 -0.1016) (xy 0.2794 0.9906) (xy -0.2794 0.9906)
			)
			(stroke
				(width 0)
				(type default)
			)
			(fill no)
			(layer "F.CrtYd")
		)
		(fp_line
			(start 0.2794 0.9906)
			(end 0.2794 -0.1016)
			(stroke
				(width 0.1)
				(type default)
			)
			(layer "F.Fab")
		)
		(fp_line
			(start 0.2794 -0.1016)
			(end -0.2794 -0.1016)
			(stroke
				(width 0.1)
				(type default)
			)
			(layer "F.Fab")
		)
		(fp_line
			(start -0.2794 0.9906)
			(end 0.2794 0.9906)
			(stroke
				(width 0.1)
				(type default)
			)
			(layer "F.Fab")
		)
		(fp_line
			(start -0.2794 -0.1016)
			(end -0.2794 0.9906)
			(stroke
				(width 0.1)
				(type default)
			)
			(layer "F.Fab")
		)
		(pad "1" smd rect
			(at 0 0 180)
			(size 0.508 0.508)
			(layers "F.Cu" "F.Mask" "F.Paste")
			(net "P3V3_STBY")
		)
		(pad "2" smd rect
			(at 0 0.889 180)
			(size 0.508 0.508)
			(layers "F.Cu" "F.Mask" "F.Paste")
			(net "UART_BMC_TXD5")
		)
		(zone
			(layer "F.Cu")
			(hatch none 0.5)
			(connect_pads
				(clearance 0)
			)
			(min_thickness 0.25)
			(keepout
				(tracks not_allowed)
				(vias allowed)
				(pads allowed)
				(copperpour not_allowed)
				(footprints allowed)
			)
			(placement
				(enabled no)
				(sheetname "")
			)
			(fill
				(thermal_gap 0.5)
				(thermal_bridge_width 0.5)
				(island_removal_mode 0)
			)
			(polygon
				(pts
					(xy 488.6452 -22.8346) (xy 488.1372 -22.8346) (xy 488.1372 -22.4536) (xy 488.6452 -22.4536)
				)
			)
		)
		(zone
			(layer "F.Cu")
			(hatch none 0.5)
			(connect_pads
				(clearance 0)
			)
			(min_thickness 0.25)
			(keepout
				(tracks allowed)
				(vias not_allowed)
				(pads allowed)
				(copperpour not_allowed)
				(footprints allowed)
			)
			(placement
				(enabled no)
				(sheetname "")
			)
			(fill
				(thermal_gap 0.5)
				(thermal_bridge_width 0.5)
				(island_removal_mode 0)
			)
			(polygon
				(pts
					(xy 488.6452 -22.4536) (xy 488.1372 -22.4536) (xy 488.1372 -22.8346) (xy 488.6452 -22.8346)
				)
			)
		)
	)
	(footprint ""
		(layer "F.Cu")
		(at 4.533138 -20.77339 90)
		(property "Reference" "C1F28"
			(at 0 0 90)
			(layer "F.SilkS")
			(hide yes)
			(effects
				(font
					(size 1.27 1.27)
				)
			)
		)
		(property "Value" ""
			(at 0 0 90)
			(layer "F.Fab")
			(effects
				(font
					(size 1.27 1.27)
				)
			)
		)
		(duplicate_pad_numbers_are_jumpers no)
		(fp_rect
			(start 0.3048 -0.1016)
			(end -0.3048 0.9906)
			(stroke
				(width 0)
				(type default)
			)
			(fill no)
			(layer "F.CrtYd")
		)
		(fp_line
			(start 0.3048 -0.1016)
			(end -0.3048 -0.1016)
			(stroke
				(width 0.1)
				(type default)
			)
			(layer "F.Fab")
		)
		(fp_line
			(start -0.3048 -0.1016)
			(end -0.3048 0.9906)
			(stroke
				(width 0.1)
				(type default)
			)
			(layer "F.Fab")
		)
		(fp_line
			(start 0.3048 0.9906)
			(end 0.3048 -0.1016)
			(stroke
				(width 0.1)
				(type default)
			)
			(layer "F.Fab")
		)
		(fp_line
			(start -0.3048 0.9906)
			(end 0.3048 0.9906)
			(stroke
				(width 0.1)
				(type default)
			)
			(layer "F.Fab")
		)
		(pad "1" smd rect
			(at 0 0 90)
			(size 0.508 0.508)
			(layers "F.Cu" "F.Mask" "F.Paste")
			(net "VR_FET_SW_P12V_STBY_PVDDQ_GHJ")
		)
		(pad "2" smd rect
			(at 0 0.889 90)
			(size 0.508 0.508)
			(layers "F.Cu" "F.Mask" "F.Paste")
			(net "GND")
		)
		(zone
			(layer "F.Cu")
			(hatch none 0.5)
			(connect_pads
				(clearance 0)
			)
			(min_thickness 0.25)
			(keepout
				(tracks allowed)
				(vias not_allowed)
				(pads allowed)
				(copperpour not_allowed)
				(footprints allowed)
			)
			(placement
				(enabled no)
				(sheetname "")
			)
			(fill
				(thermal_gap 0.5)
				(thermal_bridge_width 0.5)
				(island_removal_mode 0)
			)
			(polygon
				(pts
					(xy 4.787138 -21.02739) (xy 4.787138 -20.51939) (xy 5.168138 -20.51939) (xy 5.168138 -21.02739)
				)
			)
		)
		(zone
			(layer "F.Cu")
			(hatch none 0.5)
			(connect_pads
				(clearance 0)
			)
			(min_thickness 0.25)
			(keepout
				(tracks not_allowed)
				(vias allowed)
				(pads allowed)
				(copperpour not_allowed)
				(footprints allowed)
			)
			(placement
				(enabled no)
				(sheetname "")
			)
			(fill
				(thermal_gap 0.5)
				(thermal_bridge_width 0.5)
				(island_removal_mode 0)
			)
			(polygon
				(pts
					(xy 4.787138 -21.02739) (xy 4.787138 -20.51939) (xy 5.168138 -20.51939) (xy 5.168138 -21.02739)
				)
			)
		)
	)
	(footprint ""
		(layer "F.Cu")
		(at 480.08286 -18.48739)
		(property "Reference" "C9G6"
			(at 0 0 0)
			(layer "F.SilkS")
			(hide yes)
			(effects
				(font
					(size 1.27 1.27)
				)
			)
		)
		(property "Value" ""
			(at 0 0 0)
			(layer "F.Fab")
			(effects
				(font
					(size 1.27 1.27)
				)
			)
		)
		(duplicate_pad_numbers_are_jumpers no)
		(fp_poly
			(pts
				(xy 0.3048 -0.1016) (xy 0.3048 0.9906) (xy -0.3048 0.9906) (xy -0.3048 -0.1016)
			)
			(stroke
				(width 0)
				(type default)
			)
			(fill no)
			(layer "F.CrtYd")
		)
		(fp_line
			(start -0.3048 -0.1016)
			(end -0.3048 0.9906)
			(stroke
				(width 0.1)
				(type default)
			)
			(layer "F.Fab")
		)
		(fp_line
			(start -0.3048 0.9906)
			(end 0.3048 0.9906)
			(stroke
				(width 0.1)
				(type default)
			)
			(layer "F.Fab")
		)
		(fp_line
			(start 0.3048 -0.1016)
			(end -0.3048 -0.1016)
			(stroke
				(width 0.1)
				(type default)
			)
			(layer "F.Fab")
		)
		(fp_line
			(start 0.3048 0.9906)
			(end 0.3048 -0.1016)
			(stroke
				(width 0.1)
				(type default)
			)
			(layer "F.Fab")
		)
		(pad "1" smd rect
			(at 0 0)
			(size 0.508 0.508)
			(layers "F.Cu" "F.Mask" "F.Paste")
			(net "GND_LAN_TRCT1234_C")
		)
		(pad "2" smd rect
			(at 0 0.889)
			(size 0.508 0.508)
			(layers "F.Cu" "F.Mask" "F.Paste")
			(net "GND")
		)
		(zone
			(layer "F.Cu")
			(hatch none 0.5)
			(connect_pads
				(clearance 0)
			)
			(min_thickness 0.25)
			(keepout
				(tracks allowed)
				(vias not_allowed)
				(pads allowed)
				(copperpour not_allowed)
				(footprints allowed)
			)
			(placement
				(enabled no)
				(sheetname "")
			)
			(fill
				(thermal_gap 0.5)
				(thermal_bridge_width 0.5)
				(island_removal_mode 0)
			)
			(polygon
				(pts
					(xy 479.82886 -18.23339) (xy 480.33686 -18.23339) (xy 480.33686 -17.85239) (xy 479.82886 -17.85239)
				)
			)
		)
		(zone
			(layer "F.Cu")
			(hatch none 0.5)
			(connect_pads
				(clearance 0)
			)
			(min_thickness 0.25)
			(keepout
				(tracks not_allowed)
				(vias allowed)
				(pads allowed)
				(copperpour not_allowed)
				(footprints allowed)
			)
			(placement
				(enabled no)
				(sheetname "")
			)
			(fill
				(thermal_gap 0.5)
				(thermal_bridge_width 0.5)
				(island_removal_mode 0)
			)
			(polygon
				(pts
					(xy 479.82886 -17.85239) (xy 480.33686 -17.85239) (xy 480.33686 -18.23339) (xy 479.82886 -18.23339)
				)
			)
		)
	)
	(footprint ""
		(layer "F.Cu")
		(at 415.7345 -114.173 -90)
		(property "Reference" "R8E11"
			(at 0 0 270)
			(layer "F.SilkS")
			(hide yes)
			(effects
				(font
					(size 1.27 1.27)
				)
			)
		)
		(property "Value" ""
			(at 0 0 270)
			(layer "F.Fab")
			(effects
				(font
					(size 1.27 1.27)
				)
			)
		)
		(duplicate_pad_numbers_are_jumpers no)
		(fp_poly
			(pts
				(xy -0.2794 -0.1016) (xy 0.2794 -0.1016) (xy 0.2794 0.9906) (xy -0.2794 0.9906)
			)
			(stroke
				(width 0)
				(type default)
			)
			(fill no)
			(layer "F.CrtYd")
		)
		(fp_line
			(start -0.2794 0.9906)
			(end 0.2794 0.9906)
			(stroke
				(width 0.1)
				(type default)
			)
			(layer "F.Fab")
		)
		(fp_line
			(start 0.2794 0.9906)
			(end 0.2794 -0.1016)
			(stroke
				(width 0.1)
				(type default)
			)
			(layer "F.Fab")
		)
		(fp_line
			(start -0.2794 -0.1016)
			(end -0.2794 0.9906)
			(stroke
				(width 0.1)
				(type default)
			)
			(layer "F.Fab")
		)
		(fp_line
			(start 0.2794 -0.1016)
			(end -0.2794 -0.1016)
			(stroke
				(width 0.1)
				(type default)
			)
			(layer "F.Fab")
		)
		(pad "1" smd rect
			(at 0 0 270)
			(size 0.508 0.508)
			(layers "F.Cu" "F.Mask" "F.Paste")
			(net "FM_MEM_THERM_EVENT_LVT3_N")
		)
		(pad "2" smd rect
			(at 0 0.889 270)
			(size 0.508 0.508)
			(layers "F.Cu" "F.Mask" "F.Paste")
			(net "FM_ADR_SMI_GPIO_N")
		)
		(zone
			(layer "F.Cu")
			(hatch none 0.5)
			(connect_pads
				(clearance 0)
			)
			(min_thickness 0.25)
			(keepout
				(tracks not_allowed)
				(vias allowed)
				(pads allowed)
				(copperpour not_allowed)
				(footprints allowed)
			)
			(placement
				(enabled no)
				(sheetname "")
			)
			(fill
				(thermal_gap 0.5)
				(thermal_bridge_width 0.5)
				(island_removal_mode 0)
			)
			(polygon
				(pts
					(xy 415.0995 -114.427) (xy 415.0995 -113.919) (xy 415.4805 -113.919) (xy 415.4805 -114.427)
				)
			)
		)
		(zone
			(layer "F.Cu")
			(hatch none 0.5)
			(connect_pads
				(clearance 0)
			)
			(min_thickness 0.25)
			(keepout
				(tracks allowed)
				(vias not_allowed)
				(pads allowed)
				(copperpour not_allowed)
				(footprints allowed)
			)
			(placement
				(enabled no)
				(sheetname "")
			)
			(fill
				(thermal_gap 0.5)
				(thermal_bridge_width 0.5)
				(island_removal_mode 0)
			)
			(polygon
				(pts
					(xy 415.4805 -114.427) (xy 415.4805 -113.919) (xy 415.0995 -113.919) (xy 415.0995 -114.427)
				)
			)
		)
	)
)
